(kicad_pcb
	(version 20241229)
	(generator "pcbnew")
	(generator_version "9.0")
	(general
		(thickness 1.6296)
		(legacy_teardrops no)
	)
	(paper "A3")
	(title_block
		(title "Thunderbolt to 10GbE adapter")
		(date "2026-04-21")
		(rev "1.1.0")
		(company "Antmicro Ltd")
		(comment 1 "www.antmicro.com")
		(comment 9 "footprints 488-491 of 703")
	)
	(layers
		(0 "F.Cu" signal)
		(4 "In1.Cu" signal)
		(6 "In2.Cu" signal)
		(8 "In3.Cu" signal)
		(10 "In4.Cu" signal)
		(12 "In5.Cu" signal)
		(14 "In6.Cu" signal)
		(2 "B.Cu" signal)
		(9 "F.Adhes" user "F.Adhesive")
		(11 "B.Adhes" user "B.Adhesive")
		(13 "F.Paste" user)
		(15 "B.Paste" user)
		(5 "F.SilkS" user "F.Silkscreen")
		(7 "B.SilkS" user "B.Silkscreen")
		(1 "F.Mask" user)
		(3 "B.Mask" user)
		(17 "Dwgs.User" user "User.Drawings")
		(19 "Cmts.User" user "User.Comments")
		(21 "Eco1.User" user "User.Eco1")
		(23 "Eco2.User" user "User.Eco2")
		(25 "Edge.Cuts" user)
		(27 "Margin" user)
		(31 "F.CrtYd" user "F.Courtyard")
		(29 "B.CrtYd" user "B.Courtyard")
		(35 "F.Fab" user)
		(33 "B.Fab" user)
	)
	(footprint "antmicro-footprints:C_0402_1005Metric"
		(layer "B.Cu")
		(at 147.481866 78.260117 180)
		(descr "Capacitor SMD 0402")
		(tags "capacitor SMD 0402")
		(property "Reference" "C251"
			(at -18.618135 -9.464883 0)
			(layer "B.SilkS")
			(effects
				(font
					(size 0.7 0.7)
					(thickness 0.15)
				)
				(justify mirror)
			)
		)
		(property "Value" "C_1u_25V_0402"
			(at -1.022927 -2.155213 0)
			(layer "B.Fab")
			(effects
				(font
					(size 0.7 0.7)
					(thickness 0.15)
				)
				(justify left bottom mirror)
			)
		)
		(property "Datasheet" "https://www.murata.com/products/productdetail?partno=GRM155R61E105KE11%23"
			(at 0 0 0)
			(layer "B.Fab")
			(hide yes)
			(effects
				(font
					(size 1.27 1.27)
					(thickness 0.15)
				)
				(justify mirror)
			)
		)
		(property "Description" "SMD Multilayer Ceramic Capacitor, 1 µF, 25 V, 0402 [1005 Metric], ± 10%, X5R, GRM Series"
			(at 0 0 0)
			(layer "B.Fab")
			(hide yes)
			(effects
				(font
					(size 1.27 1.27)
					(thickness 0.15)
				)
				(justify mirror)
			)
		)
		(property "MPN" "GRM155R61E105KE11J"
			(at 0 0 180)
			(unlocked yes)
			(layer "B.Fab")
			(hide yes)
			(effects
				(font
					(size 1 1)
					(thickness 0.15)
				)
				(justify mirror)
			)
		)
		(property "Manufacturer" "Murata"
			(at 0 0 180)
			(unlocked yes)
			(layer "B.Fab")
			(hide yes)
			(effects
				(font
					(size 1 1)
					(thickness 0.15)
				)
				(justify mirror)
			)
		)
		(property "License" "Apache-2.0"
			(at 0 0 180)
			(unlocked yes)
			(layer "B.Fab")
			(hide yes)
			(effects
				(font
					(size 1 1)
					(thickness 0.15)
				)
				(justify mirror)
			)
		)
		(property "Author" "Antmicro"
			(at 0 0 180)
			(unlocked yes)
			(layer "B.Fab")
			(hide yes)
			(effects
				(font
					(size 1 1)
					(thickness 0.15)
				)
				(justify mirror)
			)
		)
		(property "Val" "1u"
			(at 0 0 180)
			(unlocked yes)
			(layer "B.Fab")
			(hide yes)
			(effects
				(font
					(size 1 1)
					(thickness 0.15)
				)
				(justify mirror)
			)
		)
		(property "Voltage" "25V"
			(at 0 0 180)
			(unlocked yes)
			(layer "B.Fab")
			(hide yes)
			(effects
				(font
					(size 1 1)
					(thickness 0.15)
				)
				(justify mirror)
			)
		)
		(property "Dielectric" "X5R"
			(at 0 0 180)
			(unlocked yes)
			(layer "B.Fab")
			(hide yes)
			(effects
				(font
					(size 1 1)
					(thickness 0.15)
				)
				(justify mirror)
			)
		)
		(sheetname "/X710-AT2 power/")
		(sheetfile "x710-at2-power.kicad_sch")
		(attr smd)
		(fp_rect
			(start -0.925 0.47)
			(end 0.925 -0.47)
			(stroke
				(width 0.05)
				(type default)
			)
			(fill no)
			(layer "B.CrtYd")
		)
		(fp_line
			(start 0.504 0.25)
			(end 0.504 -0.248)
			(stroke
				(width 0.15)
				(type solid)
			)
			(layer "B.Fab")
		)
		(fp_line
			(start 0.504 -0.248)
			(end -0.494 -0.248)
			(stroke
				(width 0.15)
				(type solid)
			)
			(layer "B.Fab")
		)
		(fp_line
			(start -0.494 0.25)
			(end 0.504 0.25)
			(stroke
				(width 0.15)
				(type solid)
			)
			(layer "B.Fab")
		)
		(fp_line
			(start -0.494 -0.248)
			(end -0.494 0.25)
			(stroke
				(width 0.15)
				(type solid)
			)
			(layer "B.Fab")
		)
		(fp_text user "${REFERENCE}"
			(at -0.939 -4.599 0)
			(layer "B.Fab")
			(effects
				(font
					(size 0.7 0.7)
					(thickness 0.15)
				)
				(justify left bottom mirror)
			)
		)
		(fp_text user "License: Apache-2.0"
			(at -0.939 -5.799 0)
			(layer "B.Fab")
			(effects
				(font
					(size 0.7 0.7)
					(thickness 0.15)
				)
				(justify left bottom mirror)
			)
		)
		(fp_text user "Author: Antmicro"
			(at -0.939 -3.399 0)
			(layer "B.Fab")
			(effects
				(font
					(size 0.7 0.7)
					(thickness 0.15)
				)
				(justify left bottom mirror)
			)
		)
		(pad "1" smd roundrect
			(at -0.48 0 180)
			(size 0.59 0.64)
			(layers "B.Cu" "B.Mask" "B.Paste")
			(roundrect_rratio 0.25)
			(net 23 "GND")
			(pintype "passive")
		)
		(pad "2" smd roundrect
			(at 0.48 0 180)
			(size 0.59 0.64)
			(layers "B.Cu" "B.Mask" "B.Paste")
			(roundrect_rratio 0.25)
			(net 9 "VCCD")
			(pintype "passive")
		)
	)
	(footprint "antmicro-footprints:R_0402_1005Metric"
		(layer "B.Cu")
		(at 142.5 116.124996 180)
		(descr "Resistor SMD 0402")
		(tags "resistor SMD 0402")
		(property "Reference" "R63"
			(at -19.75 7.450001 0)
			(layer "B.SilkS")
			(effects
				(font
					(size 0.7 0.7)
					(thickness 0.15)
				)
				(justify mirror)
			)
		)
		(property "Value" "R_10k_0402"
			(at -1.011843 -1.772047 0)
			(layer "B.Fab")
			(effects
				(font
					(size 0.7 0.7)
					(thickness 0.15)
				)
				(justify left bottom mirror)
			)
		)
		(property "Datasheet" "https://www.bourns.com/docs/product-datasheets/cr.pdf"
			(at 0 0 0)
			(layer "B.Fab")
			(hide yes)
			(effects
				(font
					(size 1.27 1.27)
					(thickness 0.15)
				)
				(justify mirror)
			)
		)
		(property "Description" "SMD Chip Resistor, 10 kohm, ± 1%, 62.5 mW, 0402 [1005 Metric], Thick Film, General Purpose"
			(at 0 0 0)
			(layer "B.Fab")
			(hide yes)
			(effects
				(font
					(size 1.27 1.27)
					(thickness 0.15)
				)
				(justify mirror)
			)
		)
		(property "MPN" "CR0402-FX-1002GLF"
			(at 0 0 180)
			(unlocked yes)
			(layer "B.Fab")
			(hide yes)
			(effects
				(font
					(size 1 1)
					(thickness 0.15)
				)
				(justify mirror)
			)
		)
		(property "Manufacturer" "Bourns"
			(at 0 0 180)
			(unlocked yes)
			(layer "B.Fab")
			(hide yes)
			(effects
				(font
					(size 1 1)
					(thickness 0.15)
				)
				(justify mirror)
			)
		)
		(property "License" "Apache-2.0"
			(at 0 0 180)
			(unlocked yes)
			(layer "B.Fab")
			(hide yes)
			(effects
				(font
					(size 1 1)
					(thickness 0.15)
				)
				(justify mirror)
			)
		)
		(property "Val" "10k"
			(at 0 0 180)
			(unlocked yes)
			(layer "B.Fab")
			(hide yes)
			(effects
				(font
					(size 1 1)
					(thickness 0.15)
				)
				(justify mirror)
			)
		)
		(property "Tolerance" "1%"
			(at 0 0 180)
			(unlocked yes)
			(layer "B.Fab")
			(hide yes)
			(effects
				(font
					(size 1 1)
					(thickness 0.15)
				)
				(justify mirror)
			)
		)
		(property "Author" "Antmicro"
			(at 0 0 180)
			(unlocked yes)
			(layer "B.Fab")
			(hide yes)
			(effects
				(font
					(size 1 1)
					(thickness 0.15)
				)
				(justify mirror)
			)
		)
		(sheetname "/TB Controller/")
		(sheetfile "tb.kicad_sch")
		(attr smd)
		(fp_rect
			(start -0.925 0.47)
			(end 0.925 -0.47)
			(stroke
				(width 0.05)
				(type default)
			)
			(fill no)
			(layer "B.CrtYd")
		)
		(fp_rect
			(start -0.5 0.25)
			(end 0.5 -0.25)
			(stroke
				(width 0.15)
				(type solid)
			)
			(fill no)
			(layer "B.Fab")
		)
		(fp_text user "Author: Antmicro"
			(at -0.95 -4.169 0)
			(layer "B.Fab")
			(effects
				(font
					(size 0.7 0.7)
					(thickness 0.15)
				)
				(justify left bottom mirror)
			)
		)
		(fp_text user "License: Apache-2.0"
			(at -0.95 -5.169 0)
			(layer "B.Fab")
			(effects
				(font
					(size 0.7 0.7)
					(thickness 0.15)
				)
				(justify left bottom mirror)
			)
		)
		(fp_text user "${REFERENCE}"
			(at -0.95 -3.168 0)
			(layer "B.Fab")
			(effects
				(font
					(size 0.7 0.7)
					(thickness 0.15)
				)
				(justify left bottom mirror)
			)
		)
		(pad "1" smd roundrect
			(at -0.48 0 180)
			(size 0.59 0.64)
			(layers "B.Cu" "B.Mask" "B.Paste")
			(roundrect_rratio 0.25)
			(net 57 "+3V3_TB")
			(pintype "passive")
		)
		(pad "2" smd roundrect
			(at 0.48 0 180)
			(size 0.59 0.64)
			(layers "B.Cu" "B.Mask" "B.Paste")
			(roundrect_rratio 0.25)
			(net 225 "Net-(U4D-TMS)")
			(pintype "passive")
		)
	)
	(footprint "antmicro-footprints:C_0402_1005Metric"
		(layer "B.Cu")
		(at 127.049999 128.324999)
		(descr "Capacitor SMD 0402")
		(tags "capacitor SMD 0402")
		(property "Reference" "C83"
			(at 21.900002 -7.700002 180)
			(layer "B.SilkS")
			(effects
				(font
					(size 0.7 0.7)
					(thickness 0.15)
				)
				(justify mirror)
			)
		)
		(property "Value" "C_1u_0402"
			(at -1.022927 -2.155213 180)
			(layer "B.Fab")
			(effects
				(font
					(size 0.7 0.7)
					(thickness 0.15)
				)
				(justify left bottom mirror)
			)
		)
		(property "Datasheet" "https://product.tdk.com/en/search/capacitor/ceramic/mlcc/info?part_no=C1005X6S1A105K050BC"
			(at 0 0 180)
			(layer "B.Fab")
			(hide yes)
			(effects
				(font
					(size 1.27 1.27)
					(thickness 0.15)
				)
				(justify mirror)
			)
		)
		(property "Description" "SMD Multilayer Ceramic Capacitor, 1 µF, 10 V, 0402 [1005 Metric], ± 10%, X6S, C"
			(at 0 0 180)
			(layer "B.Fab")
			(hide yes)
			(effects
				(font
					(size 1.27 1.27)
					(thickness 0.15)
				)
				(justify mirror)
			)
		)
		(property "MPN" "C1005X6S1A105K050BC"
			(at 0 0 0)
			(unlocked yes)
			(layer "B.Fab")
			(hide yes)
			(effects
				(font
					(size 1 1)
					(thickness 0.15)
				)
				(justify mirror)
			)
		)
		(property "Manufacturer" "TDK"
			(at 0 0 0)
			(unlocked yes)
			(layer "B.Fab")
			(hide yes)
			(effects
				(font
					(size 1 1)
					(thickness 0.15)
				)
				(justify mirror)
			)
		)
		(property "License" "Apache-2.0"
			(at 0 0 0)
			(unlocked yes)
			(layer "B.Fab")
			(hide yes)
			(effects
				(font
					(size 1 1)
					(thickness 0.15)
				)
				(justify mirror)
			)
		)
		(property "Val" "1u"
			(at 0 0 0)
			(unlocked yes)
			(layer "B.Fab")
			(hide yes)
			(effects
				(font
					(size 1 1)
					(thickness 0.15)
				)
				(justify mirror)
			)
		)
		(property "Voltage" ""
			(at 0 0 0)
			(unlocked yes)
			(layer "B.Fab")
			(hide yes)
			(effects
				(font
					(size 1 1)
					(thickness 0.15)
				)
				(justify mirror)
			)
		)
		(property "Dielectric" ""
			(at 0 0 0)
			(unlocked yes)
			(layer "B.Fab")
			(hide yes)
			(effects
				(font
					(size 1 1)
					(thickness 0.15)
				)
				(justify mirror)
			)
		)
		(property "Author" "Antmicro"
			(at 0 0 0)
			(unlocked yes)
			(layer "B.Fab")
			(hide yes)
			(effects
				(font
					(size 1 1)
					(thickness 0.15)
				)
				(justify mirror)
			)
		)
		(sheetname "/TB Controller - Power/")
		(sheetfile "tb-power.kicad_sch")
		(attr smd)
		(fp_rect
			(start -0.925 0.47)
			(end 0.925 -0.47)
			(stroke
				(width 0.05)
				(type default)
			)
			(fill no)
			(layer "B.CrtYd")
		)
		(fp_line
			(start -0.494 -0.248)
			(end -0.494 0.25)
			(stroke
				(width 0.15)
				(type solid)
			)
			(layer "B.Fab")
		)
		(fp_line
			(start -0.494 0.25)
			(end 0.504 0.25)
			(stroke
				(width 0.15)
				(type solid)
			)
			(layer "B.Fab")
		)
		(fp_line
			(start 0.504 -0.248)
			(end -0.494 -0.248)
			(stroke
				(width 0.15)
				(type solid)
			)
			(layer "B.Fab")
		)
		(fp_line
			(start 0.504 0.25)
			(end 0.504 -0.248)
			(stroke
				(width 0.15)
				(type solid)
			)
			(layer "B.Fab")
		)
		(fp_text user "Author: Antmicro"
			(at -0.939 -3.399 180)
			(layer "B.Fab")
			(effects
				(font
					(size 0.7 0.7)
					(thickness 0.15)
				)
				(justify left bottom mirror)
			)
		)
		(fp_text user "License: Apache-2.0"
			(at -0.939 -5.799 180)
			(layer "B.Fab")
			(effects
				(font
					(size 0.7 0.7)
					(thickness 0.15)
				)
				(justify left bottom mirror)
			)
		)
		(fp_text user "${REFERENCE}"
			(at -0.939 -4.599 180)
			(layer "B.Fab")
			(effects
				(font
					(size 0.7 0.7)
					(thickness 0.15)
				)
				(justify left bottom mirror)
			)
		)
		(pad "1" smd roundrect
			(at -0.48 0)
			(size 0.59 0.64)
			(layers "B.Cu" "B.Mask" "B.Paste")
			(roundrect_rratio 0.25)
			(net 23 "GND")
			(pintype "passive")
		)
		(pad "2" smd roundrect
			(at 0.48 0)
			(size 0.59 0.64)
			(layers "B.Cu" "B.Mask" "B.Paste")
			(roundrect_rratio 0.25)
			(net 68 "/TB Controller - Power/VCC_0P9")
			(pintype "passive")
		)
	)
	(footprint "antmicro-footprints:C_Pol_EIA-A"
		(layer "B.Cu")
		(at 156.6 103 -90)
		(property "Reference" "C327"
			(at -5 -1.5 90)
			(layer "B.SilkS")
			(effects
				(font
					(size 0.7 0.7)
					(thickness 0.15)
				)
				(justify left bottom mirror)
			)
		)
		(property "Value" "C_Pol_100u_6V_KEMET-T490-A"
			(at 0 -2 90)
			(layer "B.Fab")
			(effects
				(font
					(size 0.7 0.7)
					(thickness 0.15)
				)
				(justify left bottom mirror)
			)
		)
		(property "Datasheet" "https://www.kemet.com/en/us/capacitors/product/T490A107M006ATE800.html"
			(at 0 0 90)
			(layer "B.Fab")
			(hide yes)
			(effects
				(font
					(size 1.27 1.27)
					(thickness 0.15)
				)
				(justify mirror)
			)
		)
		(property "Description" "Surface Mount Tantalum Capacitor,  Solid SMD 6V 100uF 1206 20% ESR=800mOhms"
			(at 0 0 90)
			(layer "B.Fab")
			(hide yes)
			(effects
				(font
					(size 1.27 1.27)
					(thickness 0.15)
				)
				(justify mirror)
			)
		)
		(property "Val" "100u"
			(at 0 0 270)
			(unlocked yes)
			(layer "B.Fab")
			(hide yes)
			(effects
				(font
					(size 1 1)
					(thickness 0.15)
				)
				(justify mirror)
			)
		)
		(property "MPN" "T490A107M006ATE800"
			(at 0 0 270)
			(unlocked yes)
			(layer "B.Fab")
			(hide yes)
			(effects
				(font
					(size 1 1)
					(thickness 0.15)
				)
				(justify mirror)
			)
		)
		(property "Manufacturer" "KEMET"
			(at 0 0 270)
			(unlocked yes)
			(layer "B.Fab")
			(hide yes)
			(effects
				(font
					(size 1 1)
					(thickness 0.15)
				)
				(justify mirror)
			)
		)
		(property "License" "Apache-2.0"
			(at 0 0 270)
			(unlocked yes)
			(layer "B.Fab")
			(hide yes)
			(effects
				(font
					(size 1 1)
					(thickness 0.15)
				)
				(justify mirror)
			)
		)
		(property "Author" "Antmicro"
			(at 0 0 270)
			(unlocked yes)
			(layer "B.Fab")
			(hide yes)
			(effects
				(font
					(size 1 1)
					(thickness 0.15)
				)
				(justify mirror)
			)
		)
		(property "Voltage" "6V"
			(at 0 0 270)
			(unlocked yes)
			(layer "B.Fab")
			(hide yes)
			(effects
				(font
					(size 1 1)
					(thickness 0.15)
				)
				(justify mirror)
			)
		)
		(property "Dielectric" "template_dielectric"
			(at 0 0 270)
			(unlocked yes)
			(layer "B.Fab")
			(hide yes)
			(effects
				(font
					(size 1 1)
					(thickness 0.15)
				)
				(justify mirror)
			)
		)
		(sheetname "/X710-AT2 power/")
		(sheetfile "x710-at2-power.kicad_sch")
		(attr smd)
		(fp_line
			(start -1.95 1.25)
			(end -1.95 0.95)
			(stroke
				(width 0.12)
				(type solid)
			)
			(layer "B.SilkS")
		)
		(fp_line
			(start -2.1 1.1)
			(end -1.8 1.1)
			(stroke
				(width 0.12)
				(type solid)
			)
			(layer "B.SilkS")
		)
		(fp_line
			(start -1.5 0.85)
			(end 1.5 0.85)
			(stroke
				(width 0.12)
				(type solid)
			)
			(layer "B.SilkS")
		)
		(fp_line
			(start -1.5 0.75)
			(end -1.5 0.85)
			(stroke
				(width 0.12)
				(type solid)
			)
			(layer "B.SilkS")
		)
		(fp_line
			(start 1.5 0.75)
			(end 1.5 0.85)
			(stroke
				(width 0.12)
				(type solid)
			)
			(layer "B.SilkS")
		)
		(fp_line
			(start -1.5 -0.75)
			(end -1.5 -0.85)
			(stroke
				(width 0.12)
				(type solid)
			)
			(layer "B.SilkS")
		)
		(fp_line
			(start 1.5 -0.75)
			(end 1.5 -0.85)
			(stroke
				(width 0.12)
				(type solid)
			)
			(layer "B.SilkS")
		)
		(fp_line
			(start 1.5 -0.85)
			(end -1.5 -0.85)
			(stroke
				(width 0.12)
				(type solid)
			)
			(layer "B.SilkS")
		)
		(fp_line
			(start 1.7 1.05)
			(end -1.7 1.05)
			(stroke
				(width 0.05)
				(type solid)
			)
			(layer "B.CrtYd")
		)
		(fp_line
			(start -2.05 0.85)
			(end -2.05 -0.85)
			(stroke
				(width 0.05)
				(type solid)
			)
			(layer "B.CrtYd")
		)
		(fp_line
			(start -1.7 0.85)
			(end -1.7 1.05)
			(stroke
				(width 0.05)
				(type solid)
			)
			(layer "B.CrtYd")
		)
		(fp_line
			(start -1.7 0.85)
			(end -2.05 0.85)
			(stroke
				(width 0.05)
				(type solid)
			)
			(layer "B.CrtYd")
		)
		(fp_line
			(start 1.7 0.85)
			(end 1.7 1.05)
			(stroke
				(width 0.05)
				(type solid)
			)
			(layer "B.CrtYd")
		)
		(fp_line
			(start 2.05 0.85)
			(end 1.7 0.85)
			(stroke
				(width 0.05)
				(type solid)
			)
			(layer "B.CrtYd")
		)
		(fp_line
			(start 2.05 0.85)
			(end 2.05 -0.85)
			(stroke
				(width 0.05)
				(type solid)
			)
			(layer "B.CrtYd")
		)
		(fp_line
			(start -1.7 -0.85)
			(end -2.05 -0.85)
			(stroke
				(width 0.05)
				(type solid)
			)
			(layer "B.CrtYd")
		)
		(fp_line
			(start 2.05 -0.85)
			(end 1.7 -0.85)
			(stroke
				(width 0.05)
				(type solid)
			)
			(layer "B.CrtYd")
		)
		(fp_line
			(start -1.7 -1.05)
			(end -1.7 -0.85)
			(stroke
				(width 0.05)
				(type solid)
			)
			(layer "B.CrtYd")
		)
		(fp_line
			(start 1.7 -1.05)
			(end 1.7 -0.85)
			(stroke
				(width 0.05)
				(type solid)
			)
			(layer "B.CrtYd")
		)
		(fp_line
			(start 1.7 -1.05)
			(end -1.7 -1.05)
			(stroke
				(width 0.05)
				(type solid)
			)
			(layer "B.CrtYd")
		)
		(fp_rect
			(start -1.601 0.802)
			(end 1.6 -0.8)
			(stroke
				(width 0.1)
				(type solid)
			)
			(fill no)
			(layer "B.Fab")
		)
		(fp_text user "${REFERENCE}"
			(at -2.1 -4.198 90)
			(layer "B.Fab")
			(effects
				(font
					(size 0.7 0.7)
					(thickness 0.15)
				)
				(justify left bottom mirror)
			)
		)
		(fp_text user "Author: Antmicro"
			(at -2.1 -6.198 90)
			(layer "B.Fab")
			(effects
				(font
					(size 0.7 0.7)
					(thickness 0.15)
				)
				(justify left bottom mirror)
			)
		)
		(fp_text user "License: Apache-2.0"
			(at -2.1 -5.198 90)
			(layer "B.Fab")
			(effects
				(font
					(size 0.7 0.7)
					(thickness 0.15)
				)
				(justify left bottom mirror)
			)
		)
		(pad "1" smd roundrect
			(at -1.2 0 270)
			(size 1.2 1.2)
			(layers "B.Cu" "B.Mask" "B.Paste")
			(roundrect_rratio 0.1)
			(net 136 "+1V0")
			(pintype "passive")
		)
		(pad "2" smd roundrect
			(at 1.2 0 270)
			(size 1.2 1.2)
			(layers "B.Cu" "B.Mask" "B.Paste")
			(roundrect_rratio 0.1)
			(net 23 "GND")
			(pintype "passive")
		)
	)
)
